(kicad_pcb
	(version 20260206)
	(generator "pcbnew")
	(generator_version "10.0")
	(general
		(thickness 1.6)
		(legacy_teardrops no)
	)
	(paper "A4")
	(title_block
		(title "Bryce Canyon_F.DPB_16315-1-OCP.brd")
		(comment 1 "Bryce Canyon / footprints 1832-1838 of 2223")
	)
	(layers
		(0 "F.Cu" signal "TOP")
		(4 "In1.Cu" signal "L2GND")
		(6 "In2.Cu" signal "L3")
		(8 "In3.Cu" signal "L4GND")
		(10 "In4.Cu" signal "L5")
		(12 "In5.Cu" signal "L6VCC")
		(14 "In6.Cu" signal "L7VCC")
		(16 "In7.Cu" signal "L8")
		(18 "In8.Cu" signal "L9GND")
		(20 "In9.Cu" signal "L10")
		(22 "In10.Cu" signal "L11GND")
		(2 "B.Cu" signal "BOTTOM")
		(9 "F.Adhes" user "F.Adhesive")
		(11 "B.Adhes" user "B.Adhesive")
		(13 "F.Paste" user "Package Geometry/Pastemask Top")
		(15 "B.Paste" user "Package Geometry/Pastemask Bottom")
		(5 "F.SilkS" user "Ref Des/Silkscreen Top")
		(7 "B.SilkS" user "Ref Des/Silkscreen Bottom")
		(1 "F.Mask" user "Board Geometry/Soldermask Top")
		(3 "B.Mask" user "Board Geometry/Soldermask Bottom")
		(17 "Dwgs.User" user "User.Drawings")
		(19 "Cmts.User" user "User.Comments")
		(21 "Eco1.User" user "User.Eco1")
		(23 "Eco2.User" user "User.Eco2")
		(25 "Edge.Cuts" user "Board Geometry/Outline")
		(27 "Margin" user)
		(31 "F.CrtYd" user "Package Geometry/Place Bound Top")
		(29 "B.CrtYd" user "Package Geometry/Place Bound Bottom")
		(35 "F.Fab" user "Ref Des/Assembly Top")
		(33 "B.Fab" user "Ref Des/Assembly Bottom")
	)
	(footprint ""
		(layer "F.Cu")
		(at 369.624102 -164.443918 90)
		(property "Reference" "R583"
			(at 0 0 90)
			(layer "F.SilkS")
			(hide yes)
			(effects
				(font
					(size 1.27 1.27)
				)
			)
		)
		(property "Value" "200KR2F-L-GP"
			(at 0.064008 -3.993896 90)
			(unlocked yes)
			(layer "F.Fab")
			(hide yes)
			(effects
				(font
					(size 1.016 1.016)
					(thickness 0.1524)
				)
			)
		)
		(property "Device Type" "R402H16"
			(at 0.064008 -5.517896 90)
			(unlocked yes)
			(layer "F.Fab")
			(hide yes)
			(effects
				(font
					(size 1.016 1.016)
					(thickness 0.1524)
				)
			)
		)
		(duplicate_pad_numbers_are_jumpers no)
		(fp_line
			(start 0.508 -0.9398)
			(end -0.508 -0.9398)
			(stroke
				(width 0.1524)
				(type default)
			)
			(layer "F.SilkS")
		)
		(fp_line
			(start -0.508 -0.9398)
			(end -0.508 0.9398)
			(stroke
				(width 0.1524)
				(type default)
			)
			(layer "F.SilkS")
		)
		(fp_rect
			(start -0.508 0.9398)
			(end 0.508 -0.9398)
			(stroke
				(width 0)
				(type default)
			)
			(fill no)
			(layer "F.CrtYd")
		)
		(fp_rect
			(start -0.508 0.9398)
			(end 0.508 -0.9398)
			(stroke
				(width 0)
				(type default)
			)
			(fill no)
			(layer "F.Fab")
		)
		(pad "1" smd custom
			(at 0 -0.4445 90)
			(size 0.1397 0.1397)
			(layers "F.Cu" "F.Mask" "F.Paste")
			(net "SW_HDD_R19")
			(options
				(clearance outline)
				(anchor circle)
			)
			(primitives
				(gr_poly
					(pts
						(arc
							(start -0.1778 -0.2794)
							(mid -0.249642 -0.249642)
							(end -0.2794 -0.1778)
						)
						(arc
							(start -0.2794 0.1778)
							(mid -0.249642 0.249642)
							(end -0.1778 0.2794)
						)
						(arc
							(start 0.1778 0.2794)
							(mid 0.249642 0.249642)
							(end 0.2794 0.1778)
						)
						(arc
							(start 0.2794 -0.1778)
							(mid 0.249642 -0.249642)
							(end 0.1778 -0.2794)
						)
					)
					(width 0)
					(fill yes)
				)
			)
		)
		(pad "2" smd custom
			(at 0 0.4445 90)
			(size 0.1397 0.1397)
			(layers "F.Cu" "F.Mask" "F.Paste")
			(net "SW_HDD_N19")
			(options
				(clearance outline)
				(anchor circle)
			)
			(primitives
				(gr_poly
					(pts
						(arc
							(start -0.1778 -0.2794)
							(mid -0.249642 -0.249642)
							(end -0.2794 -0.1778)
						)
						(arc
							(start -0.2794 0.1778)
							(mid -0.249642 0.249642)
							(end -0.1778 0.2794)
						)
						(arc
							(start 0.1778 0.2794)
							(mid 0.249642 0.249642)
							(end 0.2794 0.1778)
						)
						(arc
							(start 0.2794 -0.1778)
							(mid 0.249642 -0.249642)
							(end 0.1778 -0.2794)
						)
					)
					(width 0)
					(fill yes)
				)
			)
		)
	)
	(footprint ""
		(layer "F.Cu")
		(at 381.4318 -295.0718 -90)
		(property "Reference" "R318"
			(at 0 0 270)
			(layer "F.SilkS")
			(hide yes)
			(effects
				(font
					(size 1.27 1.27)
				)
			)
		)
		(property "Value" "220R3F-1-GP"
			(at -0.0254 -2.5146 270)
			(unlocked yes)
			(layer "F.Fab")
			(hide yes)
			(effects
				(font
					(size 1.016 1.016)
					(thickness 0.1524)
				)
			)
		)
		(property "Device Type" "R603H22"
			(at -0.0254 -4.0386 270)
			(unlocked yes)
			(layer "F.Fab")
			(hide yes)
			(effects
				(font
					(size 1.016 1.016)
					(thickness 0.1524)
				)
			)
		)
		(duplicate_pad_numbers_are_jumpers no)
		(fp_line
			(start -0.4826 0)
			(end -0.2032 0)
			(stroke
				(width 0.2032)
				(type default)
			)
			(layer "F.SilkS")
		)
		(fp_line
			(start 0.2032 0)
			(end 0.4826 0)
			(stroke
				(width 0.2032)
				(type default)
			)
			(layer "F.SilkS")
		)
		(fp_rect
			(start -0.5842 1.3335)
			(end 0.5842 -1.3335)
			(stroke
				(width 0)
				(type default)
			)
			(fill no)
			(layer "F.CrtYd")
		)
		(fp_rect
			(start -0.5842 1.3335)
			(end 0.5842 -1.3335)
			(stroke
				(width 0)
				(type default)
			)
			(fill no)
			(layer "F.Fab")
		)
		(pad "1" smd custom
			(at 0 -0.762 270)
			(size 0.2159 0.2159)
			(layers "F.Cu" "F.Mask" "F.Paste")
			(net "HDD_PRSNT_8")
			(options
				(clearance outline)
				(anchor circle)
			)
			(primitives
				(gr_poly
					(pts
						(arc
							(start -0.3302 -0.4318)
							(mid -0.402042 -0.402042)
							(end -0.4318 -0.3302)
						)
						(arc
							(start -0.4318 0.3302)
							(mid -0.402042 0.402042)
							(end -0.3302 0.4318)
						)
						(arc
							(start 0.3302 0.4318)
							(mid 0.402042 0.402042)
							(end 0.4318 0.3302)
						)
						(arc
							(start 0.4318 -0.3302)
							(mid 0.402042 -0.402042)
							(end 0.3302 -0.4318)
						)
					)
					(width 0)
					(fill yes)
				)
			)
		)
		(pad "2" smd custom
			(at 0 0.762 270)
			(size 0.2159 0.2159)
			(layers "F.Cu" "F.Mask" "F.Paste")
			(net "DRIVE_A_8_INS")
			(options
				(clearance outline)
				(anchor circle)
			)
			(primitives
				(gr_poly
					(pts
						(arc
							(start -0.3302 -0.4318)
							(mid -0.402042 -0.402042)
							(end -0.4318 -0.3302)
						)
						(arc
							(start -0.4318 0.3302)
							(mid -0.402042 0.402042)
							(end -0.3302 0.4318)
						)
						(arc
							(start 0.3302 0.4318)
							(mid 0.402042 0.402042)
							(end 0.4318 0.3302)
						)
						(arc
							(start 0.4318 -0.3302)
							(mid 0.402042 -0.402042)
							(end 0.3302 -0.4318)
						)
					)
					(width 0)
					(fill yes)
				)
			)
		)
	)
	(footprint ""
		(layer "F.Cu")
		(at 14.842998 -59.857894)
		(property "Reference" "Q146"
			(at 0 0 0)
			(layer "F.SilkS")
			(hide yes)
			(effects
				(font
					(size 1.27 1.27)
				)
			)
		)
		(property "Value" "AO4407AL-GP"
			(at -3.707384 -1.5367 0)
			(unlocked yes)
			(layer "F.Fab")
			(hide yes)
			(effects
				(font
					(size 1.016 1.016)
					(thickness 0.1524)
				)
			)
		)
		(property "Device Type" "SOIC8H69"
			(at -3.707384 -3.0607 0)
			(unlocked yes)
			(layer "F.Fab")
			(hide yes)
			(effects
				(font
					(size 1.016 1.016)
					(thickness 0.1524)
				)
			)
		)
		(duplicate_pad_numbers_are_jumpers no)
		(fp_line
			(start -2.7432 -1.4224)
			(end -2.7432 1.4224)
			(stroke
				(width 0.1524)
				(type default)
			)
			(layer "F.SilkS")
		)
		(fp_line
			(start -2.7432 1.4224)
			(end -2.6416 1.4224)
			(stroke
				(width 0.1524)
				(type default)
			)
			(layer "F.SilkS")
		)
		(fp_line
			(start -2.7432 1.4224)
			(end 2.1336 1.4224)
			(stroke
				(width 0.1524)
				(type default)
			)
			(layer "F.SilkS")
		)
		(fp_line
			(start -2.7178 -0.508)
			(end -2.1844 -0.0508)
			(stroke
				(width 0.1524)
				(type default)
			)
			(layer "F.SilkS")
		)
		(fp_line
			(start -2.6289 3.4417)
			(end -2.6289 1.4732)
			(stroke
				(width 0.381)
				(type default)
			)
			(layer "F.SilkS")
		)
		(fp_line
			(start -2.1844 -0.0508)
			(end -2.7178 0.508)
			(stroke
				(width 0.1524)
				(type default)
			)
			(layer "F.SilkS")
		)
		(fp_line
			(start 2.1336 -1.4224)
			(end -2.7432 -1.4224)
			(stroke
				(width 0.1524)
				(type default)
			)
			(layer "F.SilkS")
		)
		(fp_line
			(start 2.1336 1.4224)
			(end 2.1336 -1.4224)
			(stroke
				(width 0.1524)
				(type default)
			)
			(layer "F.SilkS")
		)
		(fp_poly
			(pts
				(xy -2.2098 -1.4224) (xy -2.2098 1.4224) (xy 2.2098 1.4224) (xy 2.2098 -1.4224)
			)
			(stroke
				(width 0)
				(type default)
			)
			(fill yes)
			(layer "F.SilkS")
		)
		(fp_rect
			(start -2.450084 2.999994)
			(end 2.450084 -2.999994)
			(stroke
				(width 0)
				(type default)
			)
			(fill no)
			(layer "F.CrtYd")
		)
		(fp_poly
			(pts
				(xy -2.8194 3.6322) (xy -2.8194 -3.6322) (xy 2.8194 -3.6322) (xy 2.8194 1.18364) (xy 2.450084 1.18364)
				(xy 2.450084 -2.999994) (xy -2.450084 -2.999994) (xy -2.450084 2.999994) (xy 2.450084 2.999994)
				(xy 2.450084 1.18618) (xy 2.8194 1.18618) (xy 2.8194 3.6322)
			)
			(stroke
				(width 0)
				(type default)
			)
			(fill no)
			(layer "F.CrtYd")
		)
		(fp_rect
			(start -2.8194 3.6322)
			(end 2.8194 -3.6322)
			(stroke
				(width 0)
				(type default)
			)
			(fill no)
			(layer "F.Fab")
		)
		(pad "1" smd rect
			(at -1.905 2.54)
			(size 0.635 1.651)
			(layers "F.Cu" "F.Mask" "F.Paste")
			(net "P12V_A")
		)
		(pad "2" smd rect
			(at -0.635 2.54)
			(size 0.635 1.651)
			(layers "F.Cu" "F.Mask" "F.Paste")
			(net "P12V_A")
		)
		(pad "3" smd rect
			(at 0.635 2.54)
			(size 0.635 1.651)
			(layers "F.Cu" "F.Mask" "F.Paste")
			(net "P12V_A")
		)
		(pad "4" smd rect
			(at 1.905 2.54)
			(size 0.635 1.651)
			(layers "F.Cu" "F.Mask" "F.Paste")
			(net "SW_HDD_N24")
		)
		(pad "5" smd rect
			(at 1.905 -2.54)
			(size 0.635 1.651)
			(layers "F.Cu" "F.Mask" "F.Paste")
			(net "P12V_HDD24")
		)
		(pad "6" smd rect
			(at 0.635 -2.54)
			(size 0.635 1.651)
			(layers "F.Cu" "F.Mask" "F.Paste")
			(net "P12V_HDD24")
		)
		(pad "7" smd rect
			(at -0.635 -2.54)
			(size 0.635 1.651)
			(layers "F.Cu" "F.Mask" "F.Paste")
			(net "P12V_HDD24")
		)
		(pad "8" smd rect
			(at -1.905 -2.54)
			(size 0.635 1.651)
			(layers "F.Cu" "F.Mask" "F.Paste")
			(net "P12V_HDD24")
		)
	)
	(footprint ""
		(layer "F.Cu")
		(at 243.84 -394.3858 90)
		(property "Reference" "R1160"
			(at 0 0 90)
			(layer "F.SilkS")
			(hide yes)
			(effects
				(font
					(size 1.27 1.27)
				)
			)
		)
		(property "Value" "100KR2F-L1-GP"
			(at 0.064008 -3.993896 90)
			(unlocked yes)
			(layer "F.Fab")
			(hide yes)
			(effects
				(font
					(size 1.016 1.016)
					(thickness 0.1524)
				)
			)
		)
		(property "Device Type" "R402H16"
			(at 0.064008 -5.517896 90)
			(unlocked yes)
			(layer "F.Fab")
			(hide yes)
			(effects
				(font
					(size 1.016 1.016)
					(thickness 0.1524)
				)
			)
		)
		(duplicate_pad_numbers_are_jumpers no)
		(fp_line
			(start 0.508 -0.9398)
			(end -0.508 -0.9398)
			(stroke
				(width 0.1524)
				(type default)
			)
			(layer "F.SilkS")
		)
		(fp_line
			(start -0.508 -0.9398)
			(end -0.508 0.9398)
			(stroke
				(width 0.1524)
				(type default)
			)
			(layer "F.SilkS")
		)
		(fp_rect
			(start -0.508 0.9398)
			(end 0.508 -0.9398)
			(stroke
				(width 0)
				(type default)
			)
			(fill no)
			(layer "F.CrtYd")
		)
		(fp_rect
			(start -0.508 0.9398)
			(end 0.508 -0.9398)
			(stroke
				(width 0)
				(type default)
			)
			(fill no)
			(layer "F.Fab")
		)
		(pad "1" smd custom
			(at 0 -0.4445 90)
			(size 0.1397 0.1397)
			(layers "F.Cu" "F.Mask" "F.Paste")
			(net "MB3_VCAP_R")
			(options
				(clearance outline)
				(anchor circle)
			)
			(primitives
				(gr_poly
					(pts
						(arc
							(start -0.1778 -0.2794)
							(mid -0.249642 -0.249642)
							(end -0.2794 -0.1778)
						)
						(arc
							(start -0.2794 0.1778)
							(mid -0.249642 0.249642)
							(end -0.1778 0.2794)
						)
						(arc
							(start 0.1778 0.2794)
							(mid 0.249642 0.249642)
							(end 0.2794 0.1778)
						)
						(arc
							(start 0.2794 -0.1778)
							(mid 0.249642 -0.249642)
							(end 0.1778 -0.2794)
						)
					)
					(width 0)
					(fill yes)
				)
			)
		)
		(pad "2" smd custom
			(at 0 0.4445 90)
			(size 0.1397 0.1397)
			(layers "F.Cu" "F.Mask" "F.Paste")
			(net "MB3_PSET_R")
			(options
				(clearance outline)
				(anchor circle)
			)
			(primitives
				(gr_poly
					(pts
						(arc
							(start -0.1778 -0.2794)
							(mid -0.249642 -0.249642)
							(end -0.2794 -0.1778)
						)
						(arc
							(start -0.2794 0.1778)
							(mid -0.249642 0.249642)
							(end -0.1778 0.2794)
						)
						(arc
							(start 0.1778 0.2794)
							(mid 0.249642 0.249642)
							(end 0.2794 0.1778)
						)
						(arc
							(start 0.2794 -0.1778)
							(mid 0.249642 -0.249642)
							(end 0.1778 -0.2794)
						)
					)
					(width 0)
					(fill yes)
				)
			)
		)
	)
	(footprint ""
		(layer "F.Cu")
		(at 300.702472 -182.0418 90)
		(property "Reference" "C120"
			(at 0 0 90)
			(layer "F.SilkS")
			(hide yes)
			(effects
				(font
					(size 1.27 1.27)
				)
			)
		)
		(property "Value" "SC2D2U25V5KX-2-GP"
			(at -0.0762 -6.1214 90)
			(unlocked yes)
			(layer "F.Fab")
			(hide yes)
			(effects
				(font
					(size 1.016 1.016)
					(thickness 0.1524)
				)
			)
		)
		(property "Device Type" "C805H54"
			(at -0.0762 -8.1534 90)
			(unlocked yes)
			(layer "F.Fab")
			(hide yes)
			(effects
				(font
					(size 1.016 1.016)
					(thickness 0.1524)
				)
			)
		)
		(duplicate_pad_numbers_are_jumpers no)
		(fp_line
			(start 0.635 0)
			(end -0.635 0)
			(stroke
				(width 0.508)
				(type default)
			)
			(layer "F.SilkS")
		)
		(fp_rect
			(start -0.9652 1.778)
			(end 0.9652 -1.778)
			(stroke
				(width 0)
				(type default)
			)
			(fill no)
			(layer "F.CrtYd")
		)
		(fp_poly
			(pts
				(xy -0.9652 -1.778) (xy 0.9652 -1.778) (xy 0.9652 1.778) (xy -0.9652 1.778)
			)
			(stroke
				(width 0)
				(type default)
			)
			(fill no)
			(layer "F.Fab")
		)
		(pad "1" smd rect
			(at 0 -0.9652 90)
			(size 1.397 1.143)
			(layers "F.Cu" "F.Mask" "F.Paste")
			(net "P12V_B_COMP")
		)
		(pad "2" smd rect
			(at 0 0.9652 90)
			(size 1.397 1.143)
			(layers "F.Cu" "F.Mask" "F.Paste")
			(net "GND")
		)
	)
	(footprint ""
		(layer "F.Cu")
		(at 414.639252 -273.940016 90)
		(property "Reference" "VIA4"
			(at 0 0 90)
			(layer "F.SilkS")
			(hide yes)
			(effects
				(font
					(size 1.27 1.27)
				)
			)
		)
		(property "Value" "100OHM-8L-1D6MM-L18L16-GP"
			(at -3.7211 -4.5085 90)
			(unlocked yes)
			(layer "F.Fab")
			(hide yes)
			(effects
				(font
					(size 1.016 1.016)
					(thickness 0.1524)
				)
			)
		)
		(property "Device Type" "VIA-PCIE-4P-394076"
			(at -3.7211 -6.0325 90)
			(unlocked yes)
			(layer "F.Fab")
			(hide yes)
			(effects
				(font
					(size 1.016 1.016)
					(thickness 0.1524)
				)
			)
		)
		(duplicate_pad_numbers_are_jumpers no)
		(fp_rect
			(start -1.9685 0.381)
			(end 1.9685 -0.381)
			(stroke
				(width 0)
				(type default)
			)
			(fill no)
			(layer "F.CrtYd")
		)
		(fp_rect
			(start -1.9685 0.381)
			(end 1.9685 -0.381)
			(stroke
				(width 0)
				(type default)
			)
			(fill no)
			(layer "F.Fab")
		)
		(pad "1" thru_hole circle
			(at -1.5875 0 90)
			(size 0.508 0.508)
			(drill 0.254)
			(layers "*.Cu" "*.Mask")
			(remove_unused_layers no)
			(net "GND")
			(clearance 0.127)
			(thermal_gap 0.127)
		)
		(pad "2" thru_hole circle
			(at -0.5715 0 90)
			(size 0.508 0.508)
			(drill 0.254)
			(layers "*.Cu" "*.Mask")
			(remove_unused_layers no)
			(net "PHY_SCC_A_TO_DRV_A_9_DP")
			(clearance 0.127)
			(thermal_gap 0.127)
		)
		(pad "3" thru_hole circle
			(at 0.5715 0 90)
			(size 0.508 0.508)
			(drill 0.254)
			(layers "*.Cu" "*.Mask")
			(remove_unused_layers no)
			(net "PHY_SCC_A_TO_DRV_A_9_DN")
			(clearance 0.127)
			(thermal_gap 0.127)
		)
		(pad "4" thru_hole circle
			(at 1.5875 0 90)
			(size 0.508 0.508)
			(drill 0.254)
			(layers "*.Cu" "*.Mask")
			(remove_unused_layers no)
			(net "GND")
			(clearance 0.127)
			(thermal_gap 0.127)
		)
	)
	(footprint ""
		(layer "F.Cu")
		(at 223.360742 -217.653362 90)
		(property "Reference" "R418"
			(at 0 0 90)
			(layer "F.SilkS")
			(hide yes)
			(effects
				(font
					(size 1.27 1.27)
				)
			)
		)
		(property "Value" "0R2J-2-GP"
			(at 0.064008 -3.993896 90)
			(unlocked yes)
			(layer "F.Fab")
			(hide yes)
			(effects
				(font
					(size 1.016 1.016)
					(thickness 0.1524)
				)
			)
		)
		(property "Device Type" "R402H16"
			(at 0.064008 -5.517896 90)
			(unlocked yes)
			(layer "F.Fab")
			(hide yes)
			(effects
				(font
					(size 1.016 1.016)
					(thickness 0.1524)
				)
			)
		)
		(duplicate_pad_numbers_are_jumpers no)
		(fp_line
			(start 0.508 -0.9398)
			(end -0.508 -0.9398)
			(stroke
				(width 0.1524)
				(type default)
			)
			(layer "F.SilkS")
		)
		(fp_line
			(start -0.508 -0.9398)
			(end -0.508 0.9398)
			(stroke
				(width 0.1524)
				(type default)
			)
			(layer "F.SilkS")
		)
		(fp_rect
			(start -0.508 0.9398)
			(end 0.508 -0.9398)
			(stroke
				(width 0)
				(type default)
			)
			(fill no)
			(layer "F.CrtYd")
		)
		(fp_rect
			(start -0.508 0.9398)
			(end 0.508 -0.9398)
			(stroke
				(width 0)
				(type default)
			)
			(fill no)
			(layer "F.Fab")
		)
		(pad "1" smd custom
			(at 0 -0.4445 90)
			(size 0.1397 0.1397)
			(layers "F.Cu" "F.Mask" "F.Paste")
			(net "I2C_SCC_A_SDA_BUF")
			(options
				(clearance outline)
				(anchor circle)
			)
			(primitives
				(gr_poly
					(pts
						(arc
							(start -0.1778 -0.2794)
							(mid -0.249642 -0.249642)
							(end -0.2794 -0.1778)
						)
						(arc
							(start -0.2794 0.1778)
							(mid -0.249642 0.249642)
							(end -0.1778 0.2794)
						)
						(arc
							(start 0.1778 0.2794)
							(mid 0.249642 0.249642)
							(end 0.2794 0.1778)
						)
						(arc
							(start 0.2794 -0.1778)
							(mid 0.249642 -0.249642)
							(end 0.1778 -0.2794)
						)
					)
					(width 0)
					(fill yes)
				)
			)
		)
		(pad "2" smd custom
			(at 0 0.4445 90)
			(size 0.1397 0.1397)
			(layers "F.Cu" "F.Mask" "F.Paste")
			(net "I2C_SCC_A_SDA")
			(options
				(clearance outline)
				(anchor circle)
			)
			(primitives
				(gr_poly
					(pts
						(arc
							(start -0.1778 -0.2794)
							(mid -0.249642 -0.249642)
							(end -0.2794 -0.1778)
						)
						(arc
							(start -0.2794 0.1778)
							(mid -0.249642 0.249642)
							(end -0.1778 0.2794)
						)
						(arc
							(start 0.1778 0.2794)
							(mid 0.249642 0.249642)
							(end 0.2794 0.1778)
						)
						(arc
							(start 0.2794 -0.1778)
							(mid 0.249642 -0.249642)
							(end 0.1778 -0.2794)
						)
					)
					(width 0)
					(fill yes)
				)
			)
		)
	)
)
